(kicad_pcb
	(version 20260206)
	(generator "pcbnew")
	(generator_version "10.0")
	(general
		(thickness 1.6)
		(legacy_teardrops no)
	)
	(paper "A4")
	(title_block
		(title "01162023_DA0F0TEBIF0_F0T_Expander_BD_F_brd_V02_OCP.brd")
		(comment 1 "Grand Teton / footprint 4457 of 9728 (J26), pads 1-109 of 179")
	)
	(layers
		(0 "F.Cu" signal "TOP")
		(4 "In1.Cu" signal "GND")
		(6 "In2.Cu" signal "VCC")
		(8 "In3.Cu" signal "VCC1")
		(10 "In4.Cu" signal "GND1")
		(12 "In5.Cu" signal "IN1")
		(14 "In6.Cu" signal "GND2")
		(16 "In7.Cu" signal "IN2")
		(18 "In8.Cu" signal "GND3")
		(20 "In9.Cu" signal "IN3")
		(22 "In10.Cu" signal "GND4")
		(24 "In11.Cu" signal "IN4")
		(26 "In12.Cu" signal "GND5")
		(28 "In13.Cu" signal "IN5")
		(30 "In14.Cu" signal "GND6")
		(32 "In15.Cu" signal "IN6")
		(34 "In16.Cu" signal "GND7")
		(2 "B.Cu" signal "BOTTOM")
		(9 "F.Adhes" user "F.Adhesive")
		(11 "B.Adhes" user "B.Adhesive")
		(13 "F.Paste" user "Package Geometry/Pastemask Top")
		(15 "B.Paste" user "Package Geometry/Pastemask Bottom")
		(5 "F.SilkS" user "Ref Des/Silkscreen Top")
		(7 "B.SilkS" user "Ref Des/Silkscreen Bottom")
		(1 "F.Mask" user "Board Geometry/Soldermask Top")
		(3 "B.Mask" user "Board Geometry/Soldermask Bottom")
		(17 "Dwgs.User" user "User.Drawings")
		(19 "Cmts.User" user "User.Comments")
		(21 "Eco1.User" user "User.Eco1")
		(23 "Eco2.User" user "User.Eco2")
		(25 "Edge.Cuts" user "Board Geometry/Outline")
		(27 "Margin" user)
		(31 "F.CrtYd" user "Package Geometry/Place Bound Top")
		(29 "B.CrtYd" user "Package Geometry/Place Bound Bottom")
		(35 "F.Fab" user "Ref Des/Assembly Top")
		(33 "B.Fab" user "Ref Des/Assembly Bottom")
	)
	(footprint ""
		(layer "F.Cu")
		(at 395.619986 -127.700024)
		(property "Reference" "J26"
			(at -5.373116 34.736024 90)
			(unlocked yes)
			(layer "F.SilkS")
			(effects
				(font
					(size 0.7874 0.5842)
					(thickness 0.1524)
				)
				(justify left)
			)
		)
		(property "Value" ""
			(at 0 0 0)
			(layer "F.Fab")
			(effects
				(font
					(size 1.27 1.27)
				)
			)
		)
		(duplicate_pad_numbers_are_jumpers no)
		(pad "" np_thru_hole circle
			(at -0.727456 -32.485076)
			(size 1.1176 1.1176)
			(drill 1.1176)
			(layers "*.Cu" "*.Mask")
			(clearance 0.381)
			(thermal_gap 0.381)
		)
		(pad "" np_thru_hole circle
			(at 1.022604 32.485076)
			(size 1.1176 1.1176)
			(drill 1.1176)
			(layers "*.Cu" "*.Mask")
			(clearance 0.381)
			(thermal_gap 0.381)
		)
		(pad "A1" smd rect
			(at 3.322574 -18.465038 270)
			(size 0.3556 1.2192)
			(layers "F.Cu" "F.Mask" "F.Paste")
			(net "GND")
		)
		(pad "A2" smd rect
			(at 3.322574 -17.86509 270)
			(size 0.3556 1.2192)
			(layers "F.Cu" "F.Mask" "F.Paste")
			(net "GND")
		)
		(pad "A3" smd rect
			(at 3.322574 -17.264888 270)
			(size 0.3556 1.2192)
			(layers "F.Cu" "F.Mask" "F.Paste")
			(net "GND")
		)
		(pad "A4" smd rect
			(at 3.322574 -16.66494 270)
			(size 0.3556 1.2192)
			(layers "F.Cu" "F.Mask" "F.Paste")
			(net "GND")
		)
		(pad "A5" smd rect
			(at 3.322574 -16.064992 270)
			(size 0.3556 1.2192)
			(layers "F.Cu" "F.Mask" "F.Paste")
			(net "GND")
		)
		(pad "A6" smd rect
			(at 3.322574 -15.465044 270)
			(size 0.3556 1.2192)
			(layers "F.Cu" "F.Mask" "F.Paste")
			(net "GND")
		)
		(pad "A7" smd rect
			(at 3.322574 -14.865096 270)
			(size 0.3556 1.2192)
			(layers "F.Cu" "F.Mask" "F.Paste")
			(net "SMB_NIC6_LS_SCL")
		)
		(pad "A8" smd rect
			(at 3.322574 -14.264894 270)
			(size 0.3556 1.2192)
			(layers "F.Cu" "F.Mask" "F.Paste")
			(net "SMB_NIC6_LS_SDA")
		)
		(pad "A9" smd rect
			(at 3.322574 -13.664946 270)
			(size 0.3556 1.2192)
			(layers "F.Cu" "F.Mask" "F.Paste")
			(net "RST_SMB_NIC6_MUX_ISO_R_N")
		)
		(pad "A10" smd rect
			(at 3.322574 -13.064998 270)
			(size 0.3556 1.2192)
			(layers "F.Cu" "F.Mask" "F.Paste")
			(net "GND")
		)
		(pad "A11" smd rect
			(at 3.322574 -12.46505 270)
			(size 0.3556 1.2192)
			(layers "F.Cu" "F.Mask" "F.Paste")
			(net "RST_NIC6_PERST1_R_N")
		)
		(pad "A12" smd rect
			(at 3.322574 -11.865102 270)
			(size 0.3556 1.2192)
			(layers "F.Cu" "F.Mask" "F.Paste")
			(net "PRSNTB2_NIC6_N")
		)
		(pad "A13" smd rect
			(at 3.322574 -11.2649 270)
			(size 0.3556 1.2192)
			(layers "F.Cu" "F.Mask" "F.Paste")
			(net "GND")
		)
		(pad "A14" smd rect
			(at 3.322574 -10.664952 270)
			(size 0.3556 1.2192)
			(layers "F.Cu" "F.Mask" "F.Paste")
			(net "Net_2653")
		)
		(pad "A15" smd rect
			(at 3.322574 -10.065004 270)
			(size 0.3556 1.2192)
			(layers "F.Cu" "F.Mask" "F.Paste")
			(net "Net_2656")
		)
		(pad "A16" smd rect
			(at 3.322574 -9.465056 270)
			(size 0.3556 1.2192)
			(layers "F.Cu" "F.Mask" "F.Paste")
			(net "GND")
		)
		(pad "A17" smd rect
			(at 3.322574 -8.865108 270)
			(size 0.3556 1.2192)
			(layers "F.Cu" "F.Mask" "F.Paste")
			(net "P5E_PEX3_STN1_RX_DN<31>")
		)
		(pad "A18" smd rect
			(at 3.322574 -8.264906 270)
			(size 0.3556 1.2192)
			(layers "F.Cu" "F.Mask" "F.Paste")
			(net "P5E_PEX3_STN1_RX_DP<31>")
		)
		(pad "A19" smd rect
			(at 3.322574 -7.664958 270)
			(size 0.3556 1.2192)
			(layers "F.Cu" "F.Mask" "F.Paste")
			(net "GND")
		)
		(pad "A20" smd rect
			(at 3.322574 -7.06501 270)
			(size 0.3556 1.2192)
			(layers "F.Cu" "F.Mask" "F.Paste")
			(net "P5E_PEX3_STN1_RX_DN<30>")
		)
		(pad "A21" smd rect
			(at 3.322574 -6.465062 270)
			(size 0.3556 1.2192)
			(layers "F.Cu" "F.Mask" "F.Paste")
			(net "P5E_PEX3_STN1_RX_DP<30>")
		)
		(pad "A22" smd rect
			(at 3.322574 -5.865114 270)
			(size 0.3556 1.2192)
			(layers "F.Cu" "F.Mask" "F.Paste")
			(net "GND")
		)
		(pad "A23" smd rect
			(at 3.322574 -5.264912 270)
			(size 0.3556 1.2192)
			(layers "F.Cu" "F.Mask" "F.Paste")
			(net "P5E_PEX3_STN1_RX_DN<29>")
		)
		(pad "A24" smd rect
			(at 3.322574 -4.664964 270)
			(size 0.3556 1.2192)
			(layers "F.Cu" "F.Mask" "F.Paste")
			(net "P5E_PEX3_STN1_RX_DP<29>")
		)
		(pad "A25" smd rect
			(at 3.322574 -4.065016 270)
			(size 0.3556 1.2192)
			(layers "F.Cu" "F.Mask" "F.Paste")
			(net "GND")
		)
		(pad "A26" smd rect
			(at 3.322574 -3.465068 270)
			(size 0.3556 1.2192)
			(layers "F.Cu" "F.Mask" "F.Paste")
			(net "P5E_PEX3_STN1_RX_DN<28>")
		)
		(pad "A27" smd rect
			(at 3.322574 -2.86512 270)
			(size 0.3556 1.2192)
			(layers "F.Cu" "F.Mask" "F.Paste")
			(net "P5E_PEX3_STN1_RX_DP<28>")
		)
		(pad "A28" smd rect
			(at 3.322574 -2.264918 270)
			(size 0.3556 1.2192)
			(layers "F.Cu" "F.Mask" "F.Paste")
			(net "GND")
		)
		(pad "A29" smd rect
			(at 3.322574 1.74498 270)
			(size 0.3556 1.2192)
			(layers "F.Cu" "F.Mask" "F.Paste")
			(net "GND")
		)
		(pad "A30" smd rect
			(at 3.322574 2.344928 270)
			(size 0.3556 1.2192)
			(layers "F.Cu" "F.Mask" "F.Paste")
			(net "P5E_PEX3_STN1_RX_DN<27>")
		)
		(pad "A31" smd rect
			(at 3.322574 2.944876 270)
			(size 0.3556 1.2192)
			(layers "F.Cu" "F.Mask" "F.Paste")
			(net "P5E_PEX3_STN1_RX_DP<27>")
		)
		(pad "A32" smd rect
			(at 3.322574 3.545078 270)
			(size 0.3556 1.2192)
			(layers "F.Cu" "F.Mask" "F.Paste")
			(net "GND")
		)
		(pad "A33" smd rect
			(at 3.322574 4.145026 270)
			(size 0.3556 1.2192)
			(layers "F.Cu" "F.Mask" "F.Paste")
			(net "P5E_PEX3_STN1_RX_DN<26>")
		)
		(pad "A34" smd rect
			(at 3.322574 4.744974 270)
			(size 0.3556 1.2192)
			(layers "F.Cu" "F.Mask" "F.Paste")
			(net "P5E_PEX3_STN1_RX_DP<26>")
		)
		(pad "A35" smd rect
			(at 3.322574 5.344922 270)
			(size 0.3556 1.2192)
			(layers "F.Cu" "F.Mask" "F.Paste")
			(net "GND")
		)
		(pad "A36" smd rect
			(at 3.322574 5.945124 270)
			(size 0.3556 1.2192)
			(layers "F.Cu" "F.Mask" "F.Paste")
			(net "P5E_PEX3_STN1_RX_DN<25>")
		)
		(pad "A37" smd rect
			(at 3.322574 6.545072 270)
			(size 0.3556 1.2192)
			(layers "F.Cu" "F.Mask" "F.Paste")
			(net "P5E_PEX3_STN1_RX_DP<25>")
		)
		(pad "A38" smd rect
			(at 3.322574 7.14502 270)
			(size 0.3556 1.2192)
			(layers "F.Cu" "F.Mask" "F.Paste")
			(net "GND")
		)
		(pad "A39" smd rect
			(at 3.322574 7.744968 270)
			(size 0.3556 1.2192)
			(layers "F.Cu" "F.Mask" "F.Paste")
			(net "P5E_PEX3_STN1_RX_DN<24>")
		)
		(pad "A40" smd rect
			(at 3.322574 8.344916 270)
			(size 0.3556 1.2192)
			(layers "F.Cu" "F.Mask" "F.Paste")
			(net "P5E_PEX3_STN1_RX_DP<24>")
		)
		(pad "A41" smd rect
			(at 3.322574 8.945118 270)
			(size 0.3556 1.2192)
			(layers "F.Cu" "F.Mask" "F.Paste")
			(net "GND")
		)
		(pad "A42" smd rect
			(at 3.322574 9.545066 270)
			(size 0.3556 1.2192)
			(layers "F.Cu" "F.Mask" "F.Paste")
			(net "PRSNTB1_NIC6_N")
		)
		(pad "A43" smd rect
			(at 3.322574 14.454886 270)
			(size 0.3556 1.2192)
			(layers "F.Cu" "F.Mask" "F.Paste")
			(net "GND")
		)
		(pad "A44" smd rect
			(at 3.322574 15.055088 270)
			(size 0.3556 1.2192)
			(layers "F.Cu" "F.Mask" "F.Paste")
			(net "P5E_PEX3_STN1_RX_DN<23>")
		)
		(pad "A45" smd rect
			(at 3.322574 15.655036 270)
			(size 0.3556 1.2192)
			(layers "F.Cu" "F.Mask" "F.Paste")
			(net "P5E_PEX3_STN1_RX_DP<23>")
		)
		(pad "A46" smd rect
			(at 3.322574 16.254984 270)
			(size 0.3556 1.2192)
			(layers "F.Cu" "F.Mask" "F.Paste")
			(net "GND")
		)
		(pad "A47" smd rect
			(at 3.322574 16.854932 270)
			(size 0.3556 1.2192)
			(layers "F.Cu" "F.Mask" "F.Paste")
			(net "P5E_PEX3_STN1_RX_DN<22>")
		)
		(pad "A48" smd rect
			(at 3.322574 17.45488 270)
			(size 0.3556 1.2192)
			(layers "F.Cu" "F.Mask" "F.Paste")
			(net "P5E_PEX3_STN1_RX_DP<22>")
		)
		(pad "A49" smd rect
			(at 3.322574 18.055082 270)
			(size 0.3556 1.2192)
			(layers "F.Cu" "F.Mask" "F.Paste")
			(net "GND")
		)
		(pad "A50" smd rect
			(at 3.322574 18.65503 270)
			(size 0.3556 1.2192)
			(layers "F.Cu" "F.Mask" "F.Paste")
			(net "P5E_PEX3_STN1_RX_DN<21>")
		)
		(pad "A51" smd rect
			(at 3.322574 19.254978 270)
			(size 0.3556 1.2192)
			(layers "F.Cu" "F.Mask" "F.Paste")
			(net "P5E_PEX3_STN1_RX_DP<21>")
		)
		(pad "A52" smd rect
			(at 3.322574 19.854926 270)
			(size 0.3556 1.2192)
			(layers "F.Cu" "F.Mask" "F.Paste")
			(net "GND")
		)
		(pad "A53" smd rect
			(at 3.322574 20.455128 270)
			(size 0.3556 1.2192)
			(layers "F.Cu" "F.Mask" "F.Paste")
			(net "P5E_PEX3_STN1_RX_DN<20>")
		)
		(pad "A54" smd rect
			(at 3.322574 21.055076 270)
			(size 0.3556 1.2192)
			(layers "F.Cu" "F.Mask" "F.Paste")
			(net "P5E_PEX3_STN1_RX_DP<20>")
		)
		(pad "A55" smd rect
			(at 3.322574 21.655024 270)
			(size 0.3556 1.2192)
			(layers "F.Cu" "F.Mask" "F.Paste")
			(net "GND")
		)
		(pad "A56" smd rect
			(at 3.322574 22.254972 270)
			(size 0.3556 1.2192)
			(layers "F.Cu" "F.Mask" "F.Paste")
			(net "P5E_PEX3_STN1_RX_DN<19>")
		)
		(pad "A57" smd rect
			(at 3.322574 22.85492 270)
			(size 0.3556 1.2192)
			(layers "F.Cu" "F.Mask" "F.Paste")
			(net "P5E_PEX3_STN1_RX_DP<19>")
		)
		(pad "A58" smd rect
			(at 3.322574 23.455122 270)
			(size 0.3556 1.2192)
			(layers "F.Cu" "F.Mask" "F.Paste")
			(net "GND")
		)
		(pad "A59" smd rect
			(at 3.322574 24.05507 270)
			(size 0.3556 1.2192)
			(layers "F.Cu" "F.Mask" "F.Paste")
			(net "P5E_PEX3_STN1_RX_DN<18>")
		)
		(pad "A60" smd rect
			(at 3.322574 24.655018 270)
			(size 0.3556 1.2192)
			(layers "F.Cu" "F.Mask" "F.Paste")
			(net "P5E_PEX3_STN1_RX_DP<18>")
		)
		(pad "A61" smd rect
			(at 3.322574 25.254966 270)
			(size 0.3556 1.2192)
			(layers "F.Cu" "F.Mask" "F.Paste")
			(net "GND")
		)
		(pad "A62" smd rect
			(at 3.322574 25.854914 270)
			(size 0.3556 1.2192)
			(layers "F.Cu" "F.Mask" "F.Paste")
			(net "P5E_PEX3_STN1_RX_DN<17>")
		)
		(pad "A63" smd rect
			(at 3.322574 26.455116 270)
			(size 0.3556 1.2192)
			(layers "F.Cu" "F.Mask" "F.Paste")
			(net "P5E_PEX3_STN1_RX_DP<17>")
		)
		(pad "A64" smd rect
			(at 3.322574 27.055064 270)
			(size 0.3556 1.2192)
			(layers "F.Cu" "F.Mask" "F.Paste")
			(net "GND")
		)
		(pad "A65" smd rect
			(at 3.322574 27.655012 270)
			(size 0.3556 1.2192)
			(layers "F.Cu" "F.Mask" "F.Paste")
			(net "P5E_PEX3_STN1_RX_DN<16>")
		)
		(pad "A66" smd rect
			(at 3.322574 28.25496 270)
			(size 0.3556 1.2192)
			(layers "F.Cu" "F.Mask" "F.Paste")
			(net "P5E_PEX3_STN1_RX_DP<16>")
		)
		(pad "A67" smd rect
			(at 3.322574 28.854908 270)
			(size 0.3556 1.2192)
			(layers "F.Cu" "F.Mask" "F.Paste")
			(net "GND")
		)
		(pad "A68" smd rect
			(at 3.322574 29.45511 270)
			(size 0.3556 1.2192)
			(layers "F.Cu" "F.Mask" "F.Paste")
			(net "Net_2661")
		)
		(pad "A69" smd rect
			(at 3.322574 30.055058 270)
			(size 0.3556 1.2192)
			(layers "F.Cu" "F.Mask" "F.Paste")
			(net "Net_2662")
		)
		(pad "A70" smd rect
			(at 3.322574 30.655006 270)
			(size 0.3556 1.2192)
			(layers "F.Cu" "F.Mask" "F.Paste")
			(net "NIC6_PWRBRK_R_N")
		)
		(pad "B1" smd rect
			(at -1.27762 -18.465038 270)
			(size 0.3556 1.2192)
			(layers "F.Cu" "F.Mask" "F.Paste")
			(net "P12V_NIC6")
		)
		(pad "B2" smd rect
			(at -1.27762 -17.86509 270)
			(size 0.3556 1.2192)
			(layers "F.Cu" "F.Mask" "F.Paste")
			(net "P12V_NIC6")
		)
		(pad "B3" smd rect
			(at -1.27762 -17.264888 270)
			(size 0.3556 1.2192)
			(layers "F.Cu" "F.Mask" "F.Paste")
			(net "P12V_NIC6")
		)
		(pad "B4" smd rect
			(at -1.27762 -16.66494 270)
			(size 0.3556 1.2192)
			(layers "F.Cu" "F.Mask" "F.Paste")
			(net "P12V_NIC6")
		)
		(pad "B5" smd rect
			(at -1.27762 -16.064992 270)
			(size 0.3556 1.2192)
			(layers "F.Cu" "F.Mask" "F.Paste")
			(net "P12V_NIC6")
		)
		(pad "B6" smd rect
			(at -1.27762 -15.465044 270)
			(size 0.3556 1.2192)
			(layers "F.Cu" "F.Mask" "F.Paste")
			(net "P12V_NIC6")
		)
		(pad "B7" smd rect
			(at -1.27762 -14.865096 270)
			(size 0.3556 1.2192)
			(layers "F.Cu" "F.Mask" "F.Paste")
			(net "NIC6_BIF0_N")
		)
		(pad "B8" smd rect
			(at -1.27762 -14.264894 270)
			(size 0.3556 1.2192)
			(layers "F.Cu" "F.Mask" "F.Paste")
			(net "NIC6_BIF1_N")
		)
		(pad "B9" smd rect
			(at -1.27762 -13.664946 270)
			(size 0.3556 1.2192)
			(layers "F.Cu" "F.Mask" "F.Paste")
			(net "NIC6_BIF2_N")
		)
		(pad "B10" smd rect
			(at -1.27762 -13.064998 270)
			(size 0.3556 1.2192)
			(layers "F.Cu" "F.Mask" "F.Paste")
			(net "RST_NIC6_PERST0_R_N")
		)
		(pad "B11" smd rect
			(at -1.27762 -12.46505 270)
			(size 0.3556 1.2192)
			(layers "F.Cu" "F.Mask" "F.Paste")
			(net "P3V3_NIC6")
		)
		(pad "B12" smd rect
			(at -1.27762 -11.865102 270)
			(size 0.3556 1.2192)
			(layers "F.Cu" "F.Mask" "F.Paste")
			(net "NIC6_AUX_PWR_EN_R")
		)
		(pad "B13" smd rect
			(at -1.27762 -11.2649 270)
			(size 0.3556 1.2192)
			(layers "F.Cu" "F.Mask" "F.Paste")
			(net "GND")
		)
		(pad "B14" smd rect
			(at -1.27762 -10.664952 270)
			(size 0.3556 1.2192)
			(layers "F.Cu" "F.Mask" "F.Paste")
			(net "CLK_100M_DB2000QL_NIC6_R_DN")
		)
		(pad "B15" smd rect
			(at -1.27762 -10.065004 270)
			(size 0.3556 1.2192)
			(layers "F.Cu" "F.Mask" "F.Paste")
			(net "CLK_100M_DB2000QL_NIC6_R_DP")
		)
		(pad "B16" smd rect
			(at -1.27762 -9.465056 270)
			(size 0.3556 1.2192)
			(layers "F.Cu" "F.Mask" "F.Paste")
			(net "GND")
		)
		(pad "B17" smd rect
			(at -1.27762 -8.865108 270)
			(size 0.3556 1.2192)
			(layers "F.Cu" "F.Mask" "F.Paste")
			(net "P5E_PEX3_STN1_TX_C_DP<31>")
		)
		(pad "B18" smd rect
			(at -1.27762 -8.264906 270)
			(size 0.3556 1.2192)
			(layers "F.Cu" "F.Mask" "F.Paste")
			(net "P5E_PEX3_STN1_TX_C_DN<31>")
		)
		(pad "B19" smd rect
			(at -1.27762 -7.664958 270)
			(size 0.3556 1.2192)
			(layers "F.Cu" "F.Mask" "F.Paste")
			(net "GND")
		)
		(pad "B20" smd rect
			(at -1.27762 -7.06501 270)
			(size 0.3556 1.2192)
			(layers "F.Cu" "F.Mask" "F.Paste")
			(net "P5E_PEX3_STN1_TX_C_DN<30>")
		)
		(pad "B21" smd rect
			(at -1.27762 -6.465062 270)
			(size 0.3556 1.2192)
			(layers "F.Cu" "F.Mask" "F.Paste")
			(net "P5E_PEX3_STN1_TX_C_DP<30>")
		)
		(pad "B22" smd rect
			(at -1.27762 -5.865114 270)
			(size 0.3556 1.2192)
			(layers "F.Cu" "F.Mask" "F.Paste")
			(net "GND")
		)
		(pad "B23" smd rect
			(at -1.27762 -5.264912 270)
			(size 0.3556 1.2192)
			(layers "F.Cu" "F.Mask" "F.Paste")
			(net "P5E_PEX3_STN1_TX_C_DP<29>")
		)
		(pad "B24" smd rect
			(at -1.27762 -4.664964 270)
			(size 0.3556 1.2192)
			(layers "F.Cu" "F.Mask" "F.Paste")
			(net "P5E_PEX3_STN1_TX_C_DN<29>")
		)
		(pad "B25" smd rect
			(at -1.27762 -4.065016 270)
			(size 0.3556 1.2192)
			(layers "F.Cu" "F.Mask" "F.Paste")
			(net "GND")
		)
		(pad "B26" smd rect
			(at -1.27762 -3.465068 270)
			(size 0.3556 1.2192)
			(layers "F.Cu" "F.Mask" "F.Paste")
			(net "P5E_PEX3_STN1_TX_C_DN<28>")
		)
		(pad "B27" smd rect
			(at -1.27762 -2.86512 270)
			(size 0.3556 1.2192)
			(layers "F.Cu" "F.Mask" "F.Paste")
			(net "P5E_PEX3_STN1_TX_C_DP<28>")
		)
		(pad "B28" smd rect
			(at -1.27762 -2.264918 270)
			(size 0.3556 1.2192)
			(layers "F.Cu" "F.Mask" "F.Paste")
			(net "GND")
		)
		(pad "B29" smd rect
			(at -1.27762 1.74498 270)
			(size 0.3556 1.2192)
			(layers "F.Cu" "F.Mask" "F.Paste")
			(net "GND")
		)
		(pad "B30" smd rect
			(at -1.27762 2.344928 270)
			(size 0.3556 1.2192)
			(layers "F.Cu" "F.Mask" "F.Paste")
			(net "P5E_PEX3_STN1_TX_C_DP<27>")
		)
		(pad "B31" smd rect
			(at -1.27762 2.944876 270)
			(size 0.3556 1.2192)
			(layers "F.Cu" "F.Mask" "F.Paste")
			(net "P5E_PEX3_STN1_TX_C_DN<27>")
		)
		(pad "B32" smd rect
			(at -1.27762 3.545078 270)
			(size 0.3556 1.2192)
			(layers "F.Cu" "F.Mask" "F.Paste")
			(net "GND")
		)
		(pad "B33" smd rect
			(at -1.27762 4.145026 270)
			(size 0.3556 1.2192)
			(layers "F.Cu" "F.Mask" "F.Paste")
			(net "P5E_PEX3_STN1_TX_C_DN<26>")
		)
		(pad "B34" smd rect
			(at -1.27762 4.744974 270)
			(size 0.3556 1.2192)
			(layers "F.Cu" "F.Mask" "F.Paste")
			(net "P5E_PEX3_STN1_TX_C_DP<26>")
		)
		(pad "B35" smd rect
			(at -1.27762 5.344922 270)
			(size 0.3556 1.2192)
			(layers "F.Cu" "F.Mask" "F.Paste")
			(net "GND")
		)
		(pad "B36" smd rect
			(at -1.27762 5.945124 270)
			(size 0.3556 1.2192)
			(layers "F.Cu" "F.Mask" "F.Paste")
			(net "P5E_PEX3_STN1_TX_C_DP<25>")
		)
		(pad "B37" smd rect
			(at -1.27762 6.545072 270)
			(size 0.3556 1.2192)
			(layers "F.Cu" "F.Mask" "F.Paste")
			(net "P5E_PEX3_STN1_TX_C_DN<25>")
		)
	)
)
